(kicad_pcb
	(version 20260206)
	(generator "pcbnew")
	(generator_version "10.0")
	(general
		(thickness 1.6)
		(legacy_teardrops no)
	)
	(paper "A4")
	(title_block
		(title "03242023_DA0F0TMBIJ0_F0T_Motherboard_J_brd_V01_OCP.brd")
		(comment 1 "Grand Teton / footprints 879-884 of 6105")
	)
	(layers
		(0 "F.Cu" signal "TOP")
		(4 "In1.Cu" signal "GND")
		(6 "In2.Cu" signal "IN1")
		(8 "In3.Cu" signal "GND1")
		(10 "In4.Cu" signal "IN2")
		(12 "In5.Cu" signal "GND2")
		(14 "In6.Cu" signal "IN3")
		(16 "In7.Cu" signal "GND3")
		(18 "In8.Cu" signal "VCC")
		(20 "In9.Cu" signal "VCC1")
		(22 "In10.Cu" signal "GND4")
		(24 "In11.Cu" signal "IN4")
		(26 "In12.Cu" signal "GND5")
		(28 "In13.Cu" signal "IN5")
		(30 "In14.Cu" signal "GND6")
		(32 "In15.Cu" signal "IN6")
		(34 "In16.Cu" signal "GND7")
		(2 "B.Cu" signal "BOTTOM")
		(9 "F.Adhes" user "F.Adhesive")
		(11 "B.Adhes" user "B.Adhesive")
		(13 "F.Paste" user "Package Geometry/Pastemask Top")
		(15 "B.Paste" user "Package Geometry/Pastemask Bottom")
		(5 "F.SilkS" user "Ref Des/Silkscreen Top")
		(7 "B.SilkS" user "Ref Des/Silkscreen Bottom")
		(1 "F.Mask" user "Board Geometry/Soldermask Top")
		(3 "B.Mask" user "Board Geometry/Soldermask Bottom")
		(17 "Dwgs.User" user "User.Drawings")
		(19 "Cmts.User" user "User.Comments")
		(21 "Eco1.User" user "User.Eco1")
		(23 "Eco2.User" user "User.Eco2")
		(25 "Edge.Cuts" user "Board Geometry/Outline")
		(27 "Margin" user)
		(31 "F.CrtYd" user "Package Geometry/Place Bound Top")
		(29 "B.CrtYd" user "Package Geometry/Place Bound Bottom")
		(35 "F.Fab" user "Ref Des/Assembly Top")
		(33 "B.Fab" user "Ref Des/Assembly Bottom")
	)
	(footprint ""
		(layer "F.Cu")
		(at 447.510154 -118.336822)
		(property "Reference" "R3037"
			(at 0 0 0)
			(layer "F.SilkS")
			(hide yes)
			(effects
				(font
					(size 1.27 1.27)
				)
			)
		)
		(property "Value" ""
			(at 0 0 0)
			(layer "F.Fab")
			(effects
				(font
					(size 1.27 1.27)
				)
			)
		)
		(duplicate_pad_numbers_are_jumpers no)
		(fp_line
			(start -0.7874 -0.4064)
			(end 0.7874 -0.4064)
			(stroke
				(width 0.1524)
				(type default)
			)
			(layer "F.SilkS")
		)
		(fp_line
			(start -0.7874 0.4064)
			(end -0.7874 -0.4064)
			(stroke
				(width 0.1524)
				(type default)
			)
			(layer "F.SilkS")
		)
		(fp_line
			(start 0.7874 -0.4064)
			(end 0.7874 0.4064)
			(stroke
				(width 0.1524)
				(type default)
			)
			(layer "F.SilkS")
		)
		(fp_line
			(start 0.7874 0.4064)
			(end -0.7874 0.4064)
			(stroke
				(width 0.1524)
				(type default)
			)
			(layer "F.SilkS")
		)
		(fp_line
			(start -0.67945 -0.305054)
			(end -0.12065 -0.305054)
			(stroke
				(width 0.1)
				(type default)
			)
			(layer "F.Fab")
		)
		(fp_line
			(start -0.67945 0.3048)
			(end -0.67945 -0.305054)
			(stroke
				(width 0.1)
				(type default)
			)
			(layer "F.Fab")
		)
		(fp_line
			(start -0.12065 -0.305054)
			(end -0.12065 -0.2794)
			(stroke
				(width 0.1)
				(type default)
			)
			(layer "F.Fab")
		)
		(fp_line
			(start -0.12065 -0.2794)
			(end 0.12065 -0.2794)
			(stroke
				(width 0.1)
				(type default)
			)
			(layer "F.Fab")
		)
		(fp_line
			(start -0.12065 0.2794)
			(end -0.12065 0.3048)
			(stroke
				(width 0.1)
				(type default)
			)
			(layer "F.Fab")
		)
		(fp_line
			(start -0.12065 0.3048)
			(end -0.67945 0.3048)
			(stroke
				(width 0.1)
				(type default)
			)
			(layer "F.Fab")
		)
		(fp_line
			(start 0.120396 0.2794)
			(end -0.12065 0.2794)
			(stroke
				(width 0.1)
				(type default)
			)
			(layer "F.Fab")
		)
		(fp_line
			(start 0.120396 0.3048)
			(end 0.120396 0.2794)
			(stroke
				(width 0.1)
				(type default)
			)
			(layer "F.Fab")
		)
		(fp_line
			(start 0.12065 -0.3048)
			(end 0.67945 -0.3048)
			(stroke
				(width 0.1)
				(type default)
			)
			(layer "F.Fab")
		)
		(fp_line
			(start 0.12065 -0.2794)
			(end 0.12065 -0.3048)
			(stroke
				(width 0.1)
				(type default)
			)
			(layer "F.Fab")
		)
		(fp_line
			(start 0.67945 -0.3048)
			(end 0.67945 0.3048)
			(stroke
				(width 0.1)
				(type default)
			)
			(layer "F.Fab")
		)
		(fp_line
			(start 0.67945 0.3048)
			(end 0.120396 0.3048)
			(stroke
				(width 0.1)
				(type default)
			)
			(layer "F.Fab")
		)
		(pad "1" smd circle
			(at -0.40005 0)
			(size 0 0)
			(layers "F.Cu" "F.Mask" "F.Paste")
			(net "P3V3_AUX")
		)
		(pad "2" smd circle
			(at 0.40005 0)
			(size 0 0)
			(layers "F.Cu" "F.Mask" "F.Paste")
			(net "PD_SMB_OCP1_HP_ADD1")
		)
	)
	(footprint ""
		(layer "F.Cu")
		(at 117.526816 -252.956568 -90)
		(property "Reference" "C281"
			(at 0 0 270)
			(layer "F.SilkS")
			(hide yes)
			(effects
				(font
					(size 1.27 1.27)
				)
			)
		)
		(property "Value" ""
			(at 0 0 270)
			(layer "F.Fab")
			(effects
				(font
					(size 1.27 1.27)
				)
			)
		)
		(duplicate_pad_numbers_are_jumpers no)
		(fp_line
			(start -0.7874 0.4064)
			(end -0.7874 -0.4064)
			(stroke
				(width 0.1524)
				(type default)
			)
			(layer "F.SilkS")
		)
		(fp_line
			(start 0.7874 0.4064)
			(end -0.7874 0.4064)
			(stroke
				(width 0.1524)
				(type default)
			)
			(layer "F.SilkS")
		)
		(fp_line
			(start -0.7874 -0.4064)
			(end 0.7874 -0.4064)
			(stroke
				(width 0.1524)
				(type default)
			)
			(layer "F.SilkS")
		)
		(fp_line
			(start 0.7874 -0.4064)
			(end 0.7874 0.4064)
			(stroke
				(width 0.1524)
				(type default)
			)
			(layer "F.SilkS")
		)
		(fp_line
			(start -0.67945 0.3048)
			(end -0.67945 -0.305054)
			(stroke
				(width 0.1)
				(type default)
			)
			(layer "F.Fab")
		)
		(fp_line
			(start -0.12065 0.3048)
			(end -0.67945 0.3048)
			(stroke
				(width 0.1)
				(type default)
			)
			(layer "F.Fab")
		)
		(fp_line
			(start 0.120396 0.3048)
			(end 0.120396 0.2794)
			(stroke
				(width 0.1)
				(type default)
			)
			(layer "F.Fab")
		)
		(fp_line
			(start 0.67945 0.3048)
			(end 0.120396 0.3048)
			(stroke
				(width 0.1)
				(type default)
			)
			(layer "F.Fab")
		)
		(fp_line
			(start -0.12065 0.2794)
			(end -0.12065 0.3048)
			(stroke
				(width 0.1)
				(type default)
			)
			(layer "F.Fab")
		)
		(fp_line
			(start 0.120396 0.2794)
			(end -0.12065 0.2794)
			(stroke
				(width 0.1)
				(type default)
			)
			(layer "F.Fab")
		)
		(fp_line
			(start -0.12065 -0.2794)
			(end 0.12065 -0.2794)
			(stroke
				(width 0.1)
				(type default)
			)
			(layer "F.Fab")
		)
		(fp_line
			(start 0.12065 -0.2794)
			(end 0.12065 -0.3048)
			(stroke
				(width 0.1)
				(type default)
			)
			(layer "F.Fab")
		)
		(fp_line
			(start 0.12065 -0.3048)
			(end 0.67945 -0.3048)
			(stroke
				(width 0.1)
				(type default)
			)
			(layer "F.Fab")
		)
		(fp_line
			(start 0.67945 -0.3048)
			(end 0.67945 0.3048)
			(stroke
				(width 0.1)
				(type default)
			)
			(layer "F.Fab")
		)
		(fp_line
			(start -0.67945 -0.305054)
			(end -0.12065 -0.305054)
			(stroke
				(width 0.1)
				(type default)
			)
			(layer "F.Fab")
		)
		(fp_line
			(start -0.12065 -0.305054)
			(end -0.12065 -0.2794)
			(stroke
				(width 0.1)
				(type default)
			)
			(layer "F.Fab")
		)
		(pad "1" smd circle
			(at -0.40005 0 270)
			(size 0 0)
			(layers "F.Cu" "F.Mask" "F.Paste")
			(net "PVCCIN_CPU1")
		)
		(pad "2" smd circle
			(at 0.40005 0 270)
			(size 0 0)
			(layers "F.Cu" "F.Mask" "F.Paste")
			(net "GND")
		)
	)
	(footprint ""
		(layer "F.Cu")
		(at 30.248098 -137.99693 90)
		(property "Reference" "PR4244"
			(at 0 0 90)
			(layer "F.SilkS")
			(hide yes)
			(effects
				(font
					(size 1.27 1.27)
				)
			)
		)
		(property "Value" ""
			(at 0 0 90)
			(layer "F.Fab")
			(effects
				(font
					(size 1.27 1.27)
				)
			)
		)
		(duplicate_pad_numbers_are_jumpers no)
		(fp_line
			(start 0.7874 -0.4064)
			(end 0.7874 0.4064)
			(stroke
				(width 0.1524)
				(type default)
			)
			(layer "F.SilkS")
		)
		(fp_line
			(start -0.7874 -0.4064)
			(end 0.7874 -0.4064)
			(stroke
				(width 0.1524)
				(type default)
			)
			(layer "F.SilkS")
		)
		(fp_line
			(start 0.7874 0.4064)
			(end -0.7874 0.4064)
			(stroke
				(width 0.1524)
				(type default)
			)
			(layer "F.SilkS")
		)
		(fp_line
			(start -0.7874 0.4064)
			(end -0.7874 -0.4064)
			(stroke
				(width 0.1524)
				(type default)
			)
			(layer "F.SilkS")
		)
		(fp_line
			(start -0.12065 -0.305054)
			(end -0.12065 -0.2794)
			(stroke
				(width 0.1)
				(type default)
			)
			(layer "F.Fab")
		)
		(fp_line
			(start -0.67945 -0.305054)
			(end -0.12065 -0.305054)
			(stroke
				(width 0.1)
				(type default)
			)
			(layer "F.Fab")
		)
		(fp_line
			(start 0.67945 -0.3048)
			(end 0.67945 0.3048)
			(stroke
				(width 0.1)
				(type default)
			)
			(layer "F.Fab")
		)
		(fp_line
			(start 0.12065 -0.3048)
			(end 0.67945 -0.3048)
			(stroke
				(width 0.1)
				(type default)
			)
			(layer "F.Fab")
		)
		(fp_line
			(start 0.12065 -0.2794)
			(end 0.12065 -0.3048)
			(stroke
				(width 0.1)
				(type default)
			)
			(layer "F.Fab")
		)
		(fp_line
			(start -0.12065 -0.2794)
			(end 0.12065 -0.2794)
			(stroke
				(width 0.1)
				(type default)
			)
			(layer "F.Fab")
		)
		(fp_line
			(start 0.120396 0.2794)
			(end -0.12065 0.2794)
			(stroke
				(width 0.1)
				(type default)
			)
			(layer "F.Fab")
		)
		(fp_line
			(start -0.12065 0.2794)
			(end -0.12065 0.3048)
			(stroke
				(width 0.1)
				(type default)
			)
			(layer "F.Fab")
		)
		(fp_line
			(start 0.67945 0.3048)
			(end 0.120396 0.3048)
			(stroke
				(width 0.1)
				(type default)
			)
			(layer "F.Fab")
		)
		(fp_line
			(start 0.120396 0.3048)
			(end 0.120396 0.2794)
			(stroke
				(width 0.1)
				(type default)
			)
			(layer "F.Fab")
		)
		(fp_line
			(start -0.12065 0.3048)
			(end -0.67945 0.3048)
			(stroke
				(width 0.1)
				(type default)
			)
			(layer "F.Fab")
		)
		(fp_line
			(start -0.67945 0.3048)
			(end -0.67945 -0.305054)
			(stroke
				(width 0.1)
				(type default)
			)
			(layer "F.Fab")
		)
		(pad "1" smd circle
			(at -0.40005 0 90)
			(size 0 0)
			(layers "F.Cu" "F.Mask" "F.Paste")
			(net "NC_PVCCINFAON_CPU1_ACSP5")
		)
		(pad "2" smd circle
			(at 0.40005 0 90)
			(size 0 0)
			(layers "F.Cu" "F.Mask" "F.Paste")
			(net "GND")
		)
	)
	(footprint ""
		(layer "F.Cu")
		(at 114.91722 -296.05478)
		(property "Reference" "C240"
			(at 0 0 0)
			(layer "F.SilkS")
			(hide yes)
			(effects
				(font
					(size 1.27 1.27)
				)
			)
		)
		(property "Value" ""
			(at 0 0 0)
			(layer "F.Fab")
			(effects
				(font
					(size 1.27 1.27)
				)
			)
		)
		(duplicate_pad_numbers_are_jumpers no)
		(fp_line
			(start -1.524 -0.762)
			(end 1.524 -0.762)
			(stroke
				(width 0.1524)
				(type default)
			)
			(layer "F.SilkS")
		)
		(fp_line
			(start -1.524 0.762)
			(end -1.524 -0.762)
			(stroke
				(width 0.1524)
				(type default)
			)
			(layer "F.SilkS")
		)
		(fp_line
			(start 1.524 -0.762)
			(end 1.524 0.762)
			(stroke
				(width 0.1524)
				(type default)
			)
			(layer "F.SilkS")
		)
		(fp_line
			(start 1.524 0.762)
			(end -1.524 0.762)
			(stroke
				(width 0.1524)
				(type default)
			)
			(layer "F.SilkS")
		)
		(fp_line
			(start -1.1049 -0.724916)
			(end -1.1049 0.724916)
			(stroke
				(width 0.1)
				(type default)
			)
			(layer "F.Fab")
		)
		(fp_line
			(start -1.1049 0.724916)
			(end 1.1049 0.724916)
			(stroke
				(width 0.1)
				(type default)
			)
			(layer "F.Fab")
		)
		(fp_line
			(start 1.1049 -0.724916)
			(end -1.1049 -0.724916)
			(stroke
				(width 0.1)
				(type default)
			)
			(layer "F.Fab")
		)
		(fp_line
			(start 1.1049 0.724916)
			(end 1.1049 -0.724916)
			(stroke
				(width 0.1)
				(type default)
			)
			(layer "F.Fab")
		)
		(pad "1" smd rect
			(at -0.889 0 180)
			(size 1.016 1.27)
			(layers "F.Cu" "F.Mask" "F.Paste")
			(net "PVCCIN_CPU1")
		)
		(pad "2" smd rect
			(at 0.889 0 180)
			(size 1.016 1.27)
			(layers "F.Cu" "F.Mask" "F.Paste")
			(net "GND")
		)
	)
	(footprint ""
		(layer "F.Cu")
		(at 54.242716 -113.97869 180)
		(property "Reference" "R3714"
			(at 0 0 180)
			(layer "F.SilkS")
			(hide yes)
			(effects
				(font
					(size 1.27 1.27)
				)
			)
		)
		(property "Value" ""
			(at 0 0 180)
			(layer "F.Fab")
			(effects
				(font
					(size 1.27 1.27)
				)
			)
		)
		(duplicate_pad_numbers_are_jumpers no)
		(fp_line
			(start 0.7874 0.4064)
			(end -0.7874 0.4064)
			(stroke
				(width 0.1524)
				(type default)
			)
			(layer "F.SilkS")
		)
		(fp_line
			(start 0.7874 -0.4064)
			(end 0.7874 0.4064)
			(stroke
				(width 0.1524)
				(type default)
			)
			(layer "F.SilkS")
		)
		(fp_line
			(start -0.7874 0.4064)
			(end -0.7874 -0.4064)
			(stroke
				(width 0.1524)
				(type default)
			)
			(layer "F.SilkS")
		)
		(fp_line
			(start -0.7874 -0.4064)
			(end 0.7874 -0.4064)
			(stroke
				(width 0.1524)
				(type default)
			)
			(layer "F.SilkS")
		)
		(fp_line
			(start 0.67945 0.3048)
			(end 0.120396 0.3048)
			(stroke
				(width 0.1)
				(type default)
			)
			(layer "F.Fab")
		)
		(fp_line
			(start 0.67945 -0.3048)
			(end 0.67945 0.3048)
			(stroke
				(width 0.1)
				(type default)
			)
			(layer "F.Fab")
		)
		(fp_line
			(start 0.12065 -0.2794)
			(end 0.12065 -0.3048)
			(stroke
				(width 0.1)
				(type default)
			)
			(layer "F.Fab")
		)
		(fp_line
			(start 0.12065 -0.3048)
			(end 0.67945 -0.3048)
			(stroke
				(width 0.1)
				(type default)
			)
			(layer "F.Fab")
		)
		(fp_line
			(start 0.120396 0.3048)
			(end 0.120396 0.2794)
			(stroke
				(width 0.1)
				(type default)
			)
			(layer "F.Fab")
		)
		(fp_line
			(start 0.120396 0.2794)
			(end -0.12065 0.2794)
			(stroke
				(width 0.1)
				(type default)
			)
			(layer "F.Fab")
		)
		(fp_line
			(start -0.12065 0.3048)
			(end -0.67945 0.3048)
			(stroke
				(width 0.1)
				(type default)
			)
			(layer "F.Fab")
		)
		(fp_line
			(start -0.12065 0.2794)
			(end -0.12065 0.3048)
			(stroke
				(width 0.1)
				(type default)
			)
			(layer "F.Fab")
		)
		(fp_line
			(start -0.12065 -0.2794)
			(end 0.12065 -0.2794)
			(stroke
				(width 0.1)
				(type default)
			)
			(layer "F.Fab")
		)
		(fp_line
			(start -0.12065 -0.305054)
			(end -0.12065 -0.2794)
			(stroke
				(width 0.1)
				(type default)
			)
			(layer "F.Fab")
		)
		(fp_line
			(start -0.67945 0.3048)
			(end -0.67945 -0.305054)
			(stroke
				(width 0.1)
				(type default)
			)
			(layer "F.Fab")
		)
		(fp_line
			(start -0.67945 -0.305054)
			(end -0.12065 -0.305054)
			(stroke
				(width 0.1)
				(type default)
			)
			(layer "F.Fab")
		)
		(pad "1" smd circle
			(at -0.40005 0 180)
			(size 0 0)
			(layers "F.Cu" "F.Mask" "F.Paste")
			(net "SMB_VR_3V3AUX_SDA_R6")
		)
		(pad "2" smd circle
			(at 0.40005 0 180)
			(size 0 0)
			(layers "F.Cu" "F.Mask" "F.Paste")
			(net "SMB_VR_3V3AUX_SDA")
		)
	)
	(footprint ""
		(layer "F.Cu")
		(at 110.485682 -338.298028 -90)
		(property "Reference" "PC1359"
			(at 0 0 270)
			(layer "F.SilkS")
			(hide yes)
			(effects
				(font
					(size 1.27 1.27)
				)
			)
		)
		(property "Value" ""
			(at 0 0 270)
			(layer "F.Fab")
			(effects
				(font
					(size 1.27 1.27)
				)
			)
		)
		(duplicate_pad_numbers_are_jumpers no)
		(fp_line
			(start -0.7874 0.4064)
			(end -0.7874 -0.4064)
			(stroke
				(width 0.1524)
				(type default)
			)
			(layer "F.SilkS")
		)
		(fp_line
			(start 0.7874 0.4064)
			(end -0.7874 0.4064)
			(stroke
				(width 0.1524)
				(type default)
			)
			(layer "F.SilkS")
		)
		(fp_line
			(start -0.7874 -0.4064)
			(end 0.7874 -0.4064)
			(stroke
				(width 0.1524)
				(type default)
			)
			(layer "F.SilkS")
		)
		(fp_line
			(start 0.7874 -0.4064)
			(end 0.7874 0.4064)
			(stroke
				(width 0.1524)
				(type default)
			)
			(layer "F.SilkS")
		)
		(fp_line
			(start -0.67945 0.3048)
			(end -0.67945 -0.305054)
			(stroke
				(width 0.1)
				(type default)
			)
			(layer "F.Fab")
		)
		(fp_line
			(start -0.12065 0.3048)
			(end -0.67945 0.3048)
			(stroke
				(width 0.1)
				(type default)
			)
			(layer "F.Fab")
		)
		(fp_line
			(start 0.120396 0.3048)
			(end 0.120396 0.2794)
			(stroke
				(width 0.1)
				(type default)
			)
			(layer "F.Fab")
		)
		(fp_line
			(start 0.67945 0.3048)
			(end 0.120396 0.3048)
			(stroke
				(width 0.1)
				(type default)
			)
			(layer "F.Fab")
		)
		(fp_line
			(start -0.12065 0.2794)
			(end -0.12065 0.3048)
			(stroke
				(width 0.1)
				(type default)
			)
			(layer "F.Fab")
		)
		(fp_line
			(start 0.120396 0.2794)
			(end -0.12065 0.2794)
			(stroke
				(width 0.1)
				(type default)
			)
			(layer "F.Fab")
		)
		(fp_line
			(start -0.12065 -0.2794)
			(end 0.12065 -0.2794)
			(stroke
				(width 0.1)
				(type default)
			)
			(layer "F.Fab")
		)
		(fp_line
			(start 0.12065 -0.2794)
			(end 0.12065 -0.3048)
			(stroke
				(width 0.1)
				(type default)
			)
			(layer "F.Fab")
		)
		(fp_line
			(start 0.12065 -0.3048)
			(end 0.67945 -0.3048)
			(stroke
				(width 0.1)
				(type default)
			)
			(layer "F.Fab")
		)
		(fp_line
			(start 0.67945 -0.3048)
			(end 0.67945 0.3048)
			(stroke
				(width 0.1)
				(type default)
			)
			(layer "F.Fab")
		)
		(fp_line
			(start -0.67945 -0.305054)
			(end -0.12065 -0.305054)
			(stroke
				(width 0.1)
				(type default)
			)
			(layer "F.Fab")
		)
		(fp_line
			(start -0.12065 -0.305054)
			(end -0.12065 -0.2794)
			(stroke
				(width 0.1)
				(type default)
			)
			(layer "F.Fab")
		)
		(pad "1" smd circle
			(at -0.40005 0 270)
			(size 0 0)
			(layers "F.Cu" "F.Mask" "F.Paste")
			(net "GND")
		)
		(pad "2" smd circle
			(at 0.40005 0 270)
			(size 0 0)
			(layers "F.Cu" "F.Mask" "F.Paste")
			(net "PVCCIN_CPU1_VREF")
		)
	)
)
